(kicad_pcb
	(version 20260206)
	(generator "pcbnew")
	(generator_version "10.0")
	(general
		(thickness 1.6)
		(legacy_teardrops no)
	)
	(paper "A4")
	(title_block
		(title "12092022_DA0F0TMDCD0_F0T_Management_Board_D_brd_V3_OCP.brd")
		(comment 1 "Grand Teton / footprints 355-359 of 1440")
	)
	(layers
		(0 "F.Cu" signal "TOP")
		(4 "In1.Cu" signal "GND")
		(6 "In2.Cu" signal "IN1")
		(8 "In3.Cu" signal "GND1")
		(10 "In4.Cu" signal "IN2")
		(12 "In5.Cu" signal "VCC")
		(14 "In6.Cu" signal "VCC1")
		(16 "In7.Cu" signal "IN3")
		(18 "In8.Cu" signal "GND2")
		(20 "In9.Cu" signal "IN4")
		(22 "In10.Cu" signal "GND3")
		(2 "B.Cu" signal "BOTTOM")
		(9 "F.Adhes" user "F.Adhesive")
		(11 "B.Adhes" user "B.Adhesive")
		(13 "F.Paste" user "Package Geometry/Pastemask Top")
		(15 "B.Paste" user "Package Geometry/Pastemask Bottom")
		(5 "F.SilkS" user "Ref Des/Silkscreen Top")
		(7 "B.SilkS" user "Ref Des/Silkscreen Bottom")
		(1 "F.Mask" user "Board Geometry/Soldermask Top")
		(3 "B.Mask" user "Board Geometry/Soldermask Bottom")
		(17 "Dwgs.User" user "User.Drawings")
		(19 "Cmts.User" user "User.Comments")
		(21 "Eco1.User" user "User.Eco1")
		(23 "Eco2.User" user "User.Eco2")
		(25 "Edge.Cuts" user "Board Geometry/Outline")
		(27 "Margin" user)
		(31 "F.CrtYd" user "Package Geometry/Place Bound Top")
		(29 "B.CrtYd" user "Package Geometry/Place Bound Bottom")
		(35 "F.Fab" user "Ref Des/Assembly Top")
		(33 "B.Fab" user "Ref Des/Assembly Bottom")
	)
	(footprint ""
		(layer "F.Cu")
		(at 82.639662 -33.580324 -90)
		(property "Reference" "U39"
			(at 0.409448 2.049272 90)
			(unlocked yes)
			(layer "F.SilkS")
			(effects
				(font
					(size 0.7874 0.5842)
					(thickness 0.1524)
				)
				(justify left)
			)
		)
		(property "Value" ""
			(at 0 0 270)
			(layer "F.Fab")
			(effects
				(font
					(size 1.27 1.27)
				)
			)
		)
		(duplicate_pad_numbers_are_jumpers no)
		(fp_line
			(start -1.525016 1.525016)
			(end -0.889 1.525016)
			(stroke
				(width 0.1524)
				(type default)
			)
			(layer "F.SilkS")
		)
		(fp_line
			(start 0.9906 1.525016)
			(end 1.525016 1.525016)
			(stroke
				(width 0.1524)
				(type default)
			)
			(layer "F.SilkS")
		)
		(fp_line
			(start 1.525016 1.525016)
			(end -1.525016 1.525016)
			(stroke
				(width 0.1524)
				(type default)
			)
			(layer "F.SilkS")
		)
		(fp_line
			(start 1.525016 1.525016)
			(end 1.525016 1.3208)
			(stroke
				(width 0.1524)
				(type default)
			)
			(layer "F.SilkS")
		)
		(fp_line
			(start -1.525016 1.3208)
			(end -1.525016 1.525016)
			(stroke
				(width 0.1524)
				(type default)
			)
			(layer "F.SilkS")
		)
		(fp_line
			(start 1.525016 -1.3208)
			(end 1.525016 -1.525016)
			(stroke
				(width 0.1524)
				(type default)
			)
			(layer "F.SilkS")
		)
		(fp_line
			(start -1.525016 -1.525016)
			(end -1.525016 -1.3208)
			(stroke
				(width 0.1524)
				(type default)
			)
			(layer "F.SilkS")
		)
		(fp_line
			(start -0.8636 -1.525016)
			(end -1.525016 -1.525016)
			(stroke
				(width 0.1524)
				(type default)
			)
			(layer "F.SilkS")
		)
		(fp_line
			(start 1.525016 -1.525016)
			(end -1.525016 -1.525016)
			(stroke
				(width 0.1524)
				(type default)
			)
			(layer "F.SilkS")
		)
		(fp_line
			(start 1.525016 -1.525016)
			(end 0.9398 -1.525016)
			(stroke
				(width 0.1524)
				(type default)
			)
			(layer "F.SilkS")
		)
		(fp_poly
			(pts
				(xy -2.089404 -1.1684) (xy -2.513838 -2.017014) (xy -2.938272 -1.592834)
			)
			(stroke
				(width 0)
				(type default)
			)
			(fill yes)
			(layer "F.SilkS")
		)
		(fp_line
			(start -1.525016 1.525016)
			(end -1.525016 -1.525016)
			(stroke
				(width 0.1)
				(type default)
			)
			(layer "F.Fab")
		)
		(fp_line
			(start 1.525016 1.525016)
			(end -1.525016 1.525016)
			(stroke
				(width 0.1)
				(type default)
			)
			(layer "F.Fab")
		)
		(fp_line
			(start -1.525016 -1.525016)
			(end 1.525016 -1.525016)
			(stroke
				(width 0.1)
				(type default)
			)
			(layer "F.Fab")
		)
		(fp_line
			(start 1.525016 -1.525016)
			(end 1.525016 1.525016)
			(stroke
				(width 0.1)
				(type default)
			)
			(layer "F.Fab")
		)
		(fp_poly
			(pts
				(xy -2.0701 -0.999998) (xy -2.977896 -1.302512) (xy -2.977896 -0.697484)
			)
			(stroke
				(width 0)
				(type default)
			)
			(fill yes)
			(layer "F.Fab")
		)
		(pad "1" smd rect
			(at -1.550162 -0.999998 180)
			(size 0.2794 0.9144)
			(layers "F.Cu" "F.Mask" "F.Paste")
			(net "P2V5_AUX")
		)
		(pad "2" smd rect
			(at -1.550162 -0.500126 180)
			(size 0.2794 0.9144)
			(layers "F.Cu" "F.Mask" "F.Paste")
			(net "P2V5_AUX")
		)
		(pad "3" smd rect
			(at -1.550162 0 180)
			(size 0.2794 0.9144)
			(layers "F.Cu" "F.Mask" "F.Paste")
			(net "P2V5_AUX")
		)
		(pad "4" smd rect
			(at -1.550162 0.500126 180)
			(size 0.2794 0.9144)
			(layers "F.Cu" "F.Mask" "F.Paste")
			(net "U39_ADJ")
		)
		(pad "5" smd rect
			(at -1.550162 0.999998)
			(size 0.2794 0.9144)
			(layers "F.Cu" "F.Mask" "F.Paste")
			(net "PWRGD_P2V5_AUX_R")
		)
		(pad "6" smd rect
			(at 1.550162 0.999998)
			(size 0.2794 0.9144)
			(layers "F.Cu" "F.Mask" "F.Paste")
			(net "PWRGD_P3V3_AUX_R2")
		)
		(pad "7" smd rect
			(at 1.550162 0.500126 180)
			(size 0.2794 0.9144)
			(layers "F.Cu" "F.Mask" "F.Paste")
			(net "P3V3_AUX")
		)
		(pad "8" smd rect
			(at 1.550162 0 180)
			(size 0.2794 0.9144)
			(layers "F.Cu" "F.Mask" "F.Paste")
			(net "P3V3_AUX")
		)
		(pad "9" smd rect
			(at 1.550162 -0.500126 180)
			(size 0.2794 0.9144)
			(layers "F.Cu" "F.Mask" "F.Paste")
			(net "P3V3_AUX")
		)
		(pad "10" smd rect
			(at 1.550162 -0.999998 180)
			(size 0.2794 0.9144)
			(layers "F.Cu" "F.Mask" "F.Paste")
			(net "P5V_AUX")
		)
		(pad "TH" smd rect
			(at 0 0 270)
			(size 1.7526 2.667)
			(layers "F.Cu" "F.Mask" "F.Paste")
			(net "GND")
		)
		(zone
			(layer "F.Cu")
			(hatch none 0.5)
			(connect_pads
				(clearance 0)
			)
			(min_thickness 0.25)
			(keepout
				(tracks not_allowed)
				(vias allowed)
				(pads allowed)
				(copperpour not_allowed)
				(footprints allowed)
			)
			(placement
				(enabled no)
				(sheetname "")
			)
			(fill
				(thermal_gap 0.5)
				(thermal_bridge_width 0.5)
				(island_removal_mode 0)
			)
			(polygon
				(pts
					(xy 84.17306 -34.597086) (xy 81.12506 -34.597086) (xy 81.12506 -32.565086) (xy 84.17306 -32.565086)
					(xy 84.17306 -34.495486) (xy 84.04606 -34.495486) (xy 84.04606 -32.641286) (xy 81.22666 -32.641286)
					(xy 81.22666 -34.520886) (xy 84.17306 -34.520886)
				)
			)
		)
	)
	(footprint ""
		(layer "F.Cu")
		(at 20.193 -68.834 -90)
		(property "Reference" "R90"
			(at 0 0 270)
			(layer "F.SilkS")
			(hide yes)
			(effects
				(font
					(size 1.27 1.27)
				)
			)
		)
		(property "Value" ""
			(at 0 0 270)
			(layer "F.Fab")
			(effects
				(font
					(size 1.27 1.27)
				)
			)
		)
		(duplicate_pad_numbers_are_jumpers no)
		(fp_line
			(start -0.7874 0.4064)
			(end -0.7874 -0.4064)
			(stroke
				(width 0.1524)
				(type default)
			)
			(layer "F.SilkS")
		)
		(fp_line
			(start 0.7874 0.4064)
			(end -0.7874 0.4064)
			(stroke
				(width 0.1524)
				(type default)
			)
			(layer "F.SilkS")
		)
		(fp_line
			(start -0.7874 -0.4064)
			(end 0.7874 -0.4064)
			(stroke
				(width 0.1524)
				(type default)
			)
			(layer "F.SilkS")
		)
		(fp_line
			(start 0.7874 -0.4064)
			(end 0.7874 0.4064)
			(stroke
				(width 0.1524)
				(type default)
			)
			(layer "F.SilkS")
		)
		(fp_line
			(start -0.67945 0.3048)
			(end -0.67945 -0.305054)
			(stroke
				(width 0.1)
				(type default)
			)
			(layer "F.Fab")
		)
		(fp_line
			(start -0.12065 0.3048)
			(end -0.67945 0.3048)
			(stroke
				(width 0.1)
				(type default)
			)
			(layer "F.Fab")
		)
		(fp_line
			(start 0.120396 0.3048)
			(end 0.120396 0.2794)
			(stroke
				(width 0.1)
				(type default)
			)
			(layer "F.Fab")
		)
		(fp_line
			(start 0.67945 0.3048)
			(end 0.120396 0.3048)
			(stroke
				(width 0.1)
				(type default)
			)
			(layer "F.Fab")
		)
		(fp_line
			(start -0.12065 0.2794)
			(end -0.12065 0.3048)
			(stroke
				(width 0.1)
				(type default)
			)
			(layer "F.Fab")
		)
		(fp_line
			(start 0.120396 0.2794)
			(end -0.12065 0.2794)
			(stroke
				(width 0.1)
				(type default)
			)
			(layer "F.Fab")
		)
		(fp_line
			(start -0.12065 -0.2794)
			(end 0.12065 -0.2794)
			(stroke
				(width 0.1)
				(type default)
			)
			(layer "F.Fab")
		)
		(fp_line
			(start 0.12065 -0.2794)
			(end 0.12065 -0.3048)
			(stroke
				(width 0.1)
				(type default)
			)
			(layer "F.Fab")
		)
		(fp_line
			(start 0.12065 -0.3048)
			(end 0.67945 -0.3048)
			(stroke
				(width 0.1)
				(type default)
			)
			(layer "F.Fab")
		)
		(fp_line
			(start 0.67945 -0.3048)
			(end 0.67945 0.3048)
			(stroke
				(width 0.1)
				(type default)
			)
			(layer "F.Fab")
		)
		(fp_line
			(start -0.67945 -0.305054)
			(end -0.12065 -0.305054)
			(stroke
				(width 0.1)
				(type default)
			)
			(layer "F.Fab")
		)
		(fp_line
			(start -0.12065 -0.305054)
			(end -0.12065 -0.2794)
			(stroke
				(width 0.1)
				(type default)
			)
			(layer "F.Fab")
		)
		(pad "1" smd circle
			(at -0.40005 0 270)
			(size 0 0)
			(layers "F.Cu" "F.Mask" "F.Paste")
			(net "P3V3_AUX")
		)
		(pad "2" smd circle
			(at 0.40005 0 270)
			(size 0 0)
			(layers "F.Cu" "F.Mask" "F.Paste")
			(net "RST_SPI_BMC_FLASH_R2_N")
		)
	)
	(footprint ""
		(layer "F.Cu")
		(at 27.813 -25.908 180)
		(property "Reference" "C214"
			(at 0 0 180)
			(layer "F.SilkS")
			(hide yes)
			(effects
				(font
					(size 1.27 1.27)
				)
			)
		)
		(property "Value" ""
			(at 0 0 180)
			(layer "F.Fab")
			(effects
				(font
					(size 1.27 1.27)
				)
			)
		)
		(duplicate_pad_numbers_are_jumpers no)
		(fp_line
			(start 0.7874 0.4064)
			(end -0.7874 0.4064)
			(stroke
				(width 0.1524)
				(type default)
			)
			(layer "F.SilkS")
		)
		(fp_line
			(start 0.7874 -0.4064)
			(end 0.7874 0.4064)
			(stroke
				(width 0.1524)
				(type default)
			)
			(layer "F.SilkS")
		)
		(fp_line
			(start -0.7874 0.4064)
			(end -0.7874 -0.4064)
			(stroke
				(width 0.1524)
				(type default)
			)
			(layer "F.SilkS")
		)
		(fp_line
			(start -0.7874 -0.4064)
			(end 0.7874 -0.4064)
			(stroke
				(width 0.1524)
				(type default)
			)
			(layer "F.SilkS")
		)
		(fp_line
			(start 0.67945 0.3048)
			(end 0.120396 0.3048)
			(stroke
				(width 0.1)
				(type default)
			)
			(layer "F.Fab")
		)
		(fp_line
			(start 0.67945 -0.3048)
			(end 0.67945 0.3048)
			(stroke
				(width 0.1)
				(type default)
			)
			(layer "F.Fab")
		)
		(fp_line
			(start 0.12065 -0.2794)
			(end 0.12065 -0.3048)
			(stroke
				(width 0.1)
				(type default)
			)
			(layer "F.Fab")
		)
		(fp_line
			(start 0.12065 -0.3048)
			(end 0.67945 -0.3048)
			(stroke
				(width 0.1)
				(type default)
			)
			(layer "F.Fab")
		)
		(fp_line
			(start 0.120396 0.3048)
			(end 0.120396 0.2794)
			(stroke
				(width 0.1)
				(type default)
			)
			(layer "F.Fab")
		)
		(fp_line
			(start 0.120396 0.2794)
			(end -0.12065 0.2794)
			(stroke
				(width 0.1)
				(type default)
			)
			(layer "F.Fab")
		)
		(fp_line
			(start -0.12065 0.3048)
			(end -0.67945 0.3048)
			(stroke
				(width 0.1)
				(type default)
			)
			(layer "F.Fab")
		)
		(fp_line
			(start -0.12065 0.2794)
			(end -0.12065 0.3048)
			(stroke
				(width 0.1)
				(type default)
			)
			(layer "F.Fab")
		)
		(fp_line
			(start -0.12065 -0.2794)
			(end 0.12065 -0.2794)
			(stroke
				(width 0.1)
				(type default)
			)
			(layer "F.Fab")
		)
		(fp_line
			(start -0.12065 -0.305054)
			(end -0.12065 -0.2794)
			(stroke
				(width 0.1)
				(type default)
			)
			(layer "F.Fab")
		)
		(fp_line
			(start -0.67945 0.3048)
			(end -0.67945 -0.305054)
			(stroke
				(width 0.1)
				(type default)
			)
			(layer "F.Fab")
		)
		(fp_line
			(start -0.67945 -0.305054)
			(end -0.12065 -0.305054)
			(stroke
				(width 0.1)
				(type default)
			)
			(layer "F.Fab")
		)
		(pad "1" smd circle
			(at -0.40005 0 180)
			(size 0 0)
			(layers "F.Cu" "F.Mask" "F.Paste")
			(net "V_BMC_LS_DDC_SCL_R")
		)
		(pad "2" smd circle
			(at 0.40005 0 180)
			(size 0 0)
			(layers "F.Cu" "F.Mask" "F.Paste")
			(net "GND")
		)
	)
	(footprint ""
		(layer "F.Cu")
		(at 59.311794 -34.688526 90)
		(property "Reference" "R623"
			(at 0 0 90)
			(layer "F.SilkS")
			(hide yes)
			(effects
				(font
					(size 1.27 1.27)
				)
			)
		)
		(property "Value" ""
			(at 0 0 90)
			(layer "F.Fab")
			(effects
				(font
					(size 1.27 1.27)
				)
			)
		)
		(duplicate_pad_numbers_are_jumpers no)
		(fp_line
			(start 0.7874 -0.4064)
			(end 0.7874 0.4064)
			(stroke
				(width 0.1524)
				(type default)
			)
			(layer "F.SilkS")
		)
		(fp_line
			(start -0.7874 -0.4064)
			(end 0.7874 -0.4064)
			(stroke
				(width 0.1524)
				(type default)
			)
			(layer "F.SilkS")
		)
		(fp_line
			(start 0.7874 0.4064)
			(end -0.7874 0.4064)
			(stroke
				(width 0.1524)
				(type default)
			)
			(layer "F.SilkS")
		)
		(fp_line
			(start -0.7874 0.4064)
			(end -0.7874 -0.4064)
			(stroke
				(width 0.1524)
				(type default)
			)
			(layer "F.SilkS")
		)
		(fp_line
			(start -0.12065 -0.305054)
			(end -0.12065 -0.2794)
			(stroke
				(width 0.1)
				(type default)
			)
			(layer "F.Fab")
		)
		(fp_line
			(start -0.67945 -0.305054)
			(end -0.12065 -0.305054)
			(stroke
				(width 0.1)
				(type default)
			)
			(layer "F.Fab")
		)
		(fp_line
			(start 0.67945 -0.3048)
			(end 0.67945 0.3048)
			(stroke
				(width 0.1)
				(type default)
			)
			(layer "F.Fab")
		)
		(fp_line
			(start 0.12065 -0.3048)
			(end 0.67945 -0.3048)
			(stroke
				(width 0.1)
				(type default)
			)
			(layer "F.Fab")
		)
		(fp_line
			(start 0.12065 -0.2794)
			(end 0.12065 -0.3048)
			(stroke
				(width 0.1)
				(type default)
			)
			(layer "F.Fab")
		)
		(fp_line
			(start -0.12065 -0.2794)
			(end 0.12065 -0.2794)
			(stroke
				(width 0.1)
				(type default)
			)
			(layer "F.Fab")
		)
		(fp_line
			(start 0.120396 0.2794)
			(end -0.12065 0.2794)
			(stroke
				(width 0.1)
				(type default)
			)
			(layer "F.Fab")
		)
		(fp_line
			(start -0.12065 0.2794)
			(end -0.12065 0.3048)
			(stroke
				(width 0.1)
				(type default)
			)
			(layer "F.Fab")
		)
		(fp_line
			(start 0.67945 0.3048)
			(end 0.120396 0.3048)
			(stroke
				(width 0.1)
				(type default)
			)
			(layer "F.Fab")
		)
		(fp_line
			(start 0.120396 0.3048)
			(end 0.120396 0.2794)
			(stroke
				(width 0.1)
				(type default)
			)
			(layer "F.Fab")
		)
		(fp_line
			(start -0.12065 0.3048)
			(end -0.67945 0.3048)
			(stroke
				(width 0.1)
				(type default)
			)
			(layer "F.Fab")
		)
		(fp_line
			(start -0.67945 0.3048)
			(end -0.67945 -0.305054)
			(stroke
				(width 0.1)
				(type default)
			)
			(layer "F.Fab")
		)
		(pad "1" smd circle
			(at -0.40005 0 90)
			(size 0 0)
			(layers "F.Cu" "F.Mask" "F.Paste")
			(net "P3V3_RGM")
		)
		(pad "2" smd circle
			(at 0.40005 0 90)
			(size 0 0)
			(layers "F.Cu" "F.Mask" "F.Paste")
			(net "RST_EXTRST_N")
		)
	)
	(footprint ""
		(layer "F.Cu")
		(at 12.3444 -109.347 90)
		(property "Reference" "R564"
			(at 0 0 90)
			(layer "F.SilkS")
			(hide yes)
			(effects
				(font
					(size 1.27 1.27)
				)
			)
		)
		(property "Value" ""
			(at 0 0 90)
			(layer "F.Fab")
			(effects
				(font
					(size 1.27 1.27)
				)
			)
		)
		(duplicate_pad_numbers_are_jumpers no)
		(fp_line
			(start 0.7874 -0.4064)
			(end 0.7874 0.4064)
			(stroke
				(width 0.1524)
				(type default)
			)
			(layer "F.SilkS")
		)
		(fp_line
			(start -0.7874 -0.4064)
			(end 0.7874 -0.4064)
			(stroke
				(width 0.1524)
				(type default)
			)
			(layer "F.SilkS")
		)
		(fp_line
			(start 0.7874 0.4064)
			(end -0.7874 0.4064)
			(stroke
				(width 0.1524)
				(type default)
			)
			(layer "F.SilkS")
		)
		(fp_line
			(start -0.7874 0.4064)
			(end -0.7874 -0.4064)
			(stroke
				(width 0.1524)
				(type default)
			)
			(layer "F.SilkS")
		)
		(fp_line
			(start -0.12065 -0.305054)
			(end -0.12065 -0.2794)
			(stroke
				(width 0.1)
				(type default)
			)
			(layer "F.Fab")
		)
		(fp_line
			(start -0.67945 -0.305054)
			(end -0.12065 -0.305054)
			(stroke
				(width 0.1)
				(type default)
			)
			(layer "F.Fab")
		)
		(fp_line
			(start 0.67945 -0.3048)
			(end 0.67945 0.3048)
			(stroke
				(width 0.1)
				(type default)
			)
			(layer "F.Fab")
		)
		(fp_line
			(start 0.12065 -0.3048)
			(end 0.67945 -0.3048)
			(stroke
				(width 0.1)
				(type default)
			)
			(layer "F.Fab")
		)
		(fp_line
			(start 0.12065 -0.2794)
			(end 0.12065 -0.3048)
			(stroke
				(width 0.1)
				(type default)
			)
			(layer "F.Fab")
		)
		(fp_line
			(start -0.12065 -0.2794)
			(end 0.12065 -0.2794)
			(stroke
				(width 0.1)
				(type default)
			)
			(layer "F.Fab")
		)
		(fp_line
			(start 0.120396 0.2794)
			(end -0.12065 0.2794)
			(stroke
				(width 0.1)
				(type default)
			)
			(layer "F.Fab")
		)
		(fp_line
			(start -0.12065 0.2794)
			(end -0.12065 0.3048)
			(stroke
				(width 0.1)
				(type default)
			)
			(layer "F.Fab")
		)
		(fp_line
			(start 0.67945 0.3048)
			(end 0.120396 0.3048)
			(stroke
				(width 0.1)
				(type default)
			)
			(layer "F.Fab")
		)
		(fp_line
			(start 0.120396 0.3048)
			(end 0.120396 0.2794)
			(stroke
				(width 0.1)
				(type default)
			)
			(layer "F.Fab")
		)
		(fp_line
			(start -0.12065 0.3048)
			(end -0.67945 0.3048)
			(stroke
				(width 0.1)
				(type default)
			)
			(layer "F.Fab")
		)
		(fp_line
			(start -0.67945 0.3048)
			(end -0.67945 -0.305054)
			(stroke
				(width 0.1)
				(type default)
			)
			(layer "F.Fab")
		)
		(pad "1" smd circle
			(at -0.40005 0 90)
			(size 0 0)
			(layers "F.Cu" "F.Mask" "F.Paste")
			(net "HDD_LED_N")
		)
		(pad "2" smd circle
			(at 0.40005 0 90)
			(size 0 0)
			(layers "F.Cu" "F.Mask" "F.Paste")
			(net "HDD_LED_R_N")
		)
	)
)
